(kicad_pcb
	(version 20260206)
	(generator "pcbnew")
	(generator_version "10.0")
	(general
		(thickness 1.6)
		(legacy_teardrops no)
	)
	(paper "A4")
	(title_block
		(title "03242023_DA0F0TMBIJ0_F0T_Motherboard_J_brd_V01_OCP.brd")
		(comment 1 "Grand Teton / footprints 1820-1826 of 6105")
	)
	(layers
		(0 "F.Cu" signal "TOP")
		(4 "In1.Cu" signal "GND")
		(6 "In2.Cu" signal "IN1")
		(8 "In3.Cu" signal "GND1")
		(10 "In4.Cu" signal "IN2")
		(12 "In5.Cu" signal "GND2")
		(14 "In6.Cu" signal "IN3")
		(16 "In7.Cu" signal "GND3")
		(18 "In8.Cu" signal "VCC")
		(20 "In9.Cu" signal "VCC1")
		(22 "In10.Cu" signal "GND4")
		(24 "In11.Cu" signal "IN4")
		(26 "In12.Cu" signal "GND5")
		(28 "In13.Cu" signal "IN5")
		(30 "In14.Cu" signal "GND6")
		(32 "In15.Cu" signal "IN6")
		(34 "In16.Cu" signal "GND7")
		(2 "B.Cu" signal "BOTTOM")
		(9 "F.Adhes" user "F.Adhesive")
		(11 "B.Adhes" user "B.Adhesive")
		(13 "F.Paste" user "Package Geometry/Pastemask Top")
		(15 "B.Paste" user "Package Geometry/Pastemask Bottom")
		(5 "F.SilkS" user "Ref Des/Silkscreen Top")
		(7 "B.SilkS" user "Ref Des/Silkscreen Bottom")
		(1 "F.Mask" user "Board Geometry/Soldermask Top")
		(3 "B.Mask" user "Board Geometry/Soldermask Bottom")
		(17 "Dwgs.User" user "User.Drawings")
		(19 "Cmts.User" user "User.Comments")
		(21 "Eco1.User" user "User.Eco1")
		(23 "Eco2.User" user "User.Eco2")
		(25 "Edge.Cuts" user "Board Geometry/Outline")
		(27 "Margin" user)
		(31 "F.CrtYd" user "Package Geometry/Place Bound Top")
		(29 "B.CrtYd" user "Package Geometry/Place Bound Bottom")
		(35 "F.Fab" user "Ref Des/Assembly Top")
		(33 "B.Fab" user "Ref Des/Assembly Bottom")
	)
	(footprint ""
		(layer "F.Cu")
		(at 120.57888 -92.674948 -90)
		(property "Reference" "R4395"
			(at 0 0 270)
			(layer "F.SilkS")
			(hide yes)
			(effects
				(font
					(size 1.27 1.27)
				)
			)
		)
		(property "Value" ""
			(at 0 0 270)
			(layer "F.Fab")
			(effects
				(font
					(size 1.27 1.27)
				)
			)
		)
		(duplicate_pad_numbers_are_jumpers no)
		(fp_line
			(start -0.7874 0.4064)
			(end -0.7874 -0.4064)
			(stroke
				(width 0.1524)
				(type default)
			)
			(layer "F.SilkS")
		)
		(fp_line
			(start 0.7874 0.4064)
			(end -0.7874 0.4064)
			(stroke
				(width 0.1524)
				(type default)
			)
			(layer "F.SilkS")
		)
		(fp_line
			(start -0.7874 -0.4064)
			(end 0.7874 -0.4064)
			(stroke
				(width 0.1524)
				(type default)
			)
			(layer "F.SilkS")
		)
		(fp_line
			(start 0.7874 -0.4064)
			(end 0.7874 0.4064)
			(stroke
				(width 0.1524)
				(type default)
			)
			(layer "F.SilkS")
		)
		(fp_line
			(start -0.67945 0.3048)
			(end -0.67945 -0.305054)
			(stroke
				(width 0.1)
				(type default)
			)
			(layer "F.Fab")
		)
		(fp_line
			(start -0.12065 0.3048)
			(end -0.67945 0.3048)
			(stroke
				(width 0.1)
				(type default)
			)
			(layer "F.Fab")
		)
		(fp_line
			(start 0.120396 0.3048)
			(end 0.120396 0.2794)
			(stroke
				(width 0.1)
				(type default)
			)
			(layer "F.Fab")
		)
		(fp_line
			(start 0.67945 0.3048)
			(end 0.120396 0.3048)
			(stroke
				(width 0.1)
				(type default)
			)
			(layer "F.Fab")
		)
		(fp_line
			(start -0.12065 0.2794)
			(end -0.12065 0.3048)
			(stroke
				(width 0.1)
				(type default)
			)
			(layer "F.Fab")
		)
		(fp_line
			(start 0.120396 0.2794)
			(end -0.12065 0.2794)
			(stroke
				(width 0.1)
				(type default)
			)
			(layer "F.Fab")
		)
		(fp_line
			(start -0.12065 -0.2794)
			(end 0.12065 -0.2794)
			(stroke
				(width 0.1)
				(type default)
			)
			(layer "F.Fab")
		)
		(fp_line
			(start 0.12065 -0.2794)
			(end 0.12065 -0.3048)
			(stroke
				(width 0.1)
				(type default)
			)
			(layer "F.Fab")
		)
		(fp_line
			(start 0.12065 -0.3048)
			(end 0.67945 -0.3048)
			(stroke
				(width 0.1)
				(type default)
			)
			(layer "F.Fab")
		)
		(fp_line
			(start 0.67945 -0.3048)
			(end 0.67945 0.3048)
			(stroke
				(width 0.1)
				(type default)
			)
			(layer "F.Fab")
		)
		(fp_line
			(start -0.67945 -0.305054)
			(end -0.12065 -0.305054)
			(stroke
				(width 0.1)
				(type default)
			)
			(layer "F.Fab")
		)
		(fp_line
			(start -0.12065 -0.305054)
			(end -0.12065 -0.2794)
			(stroke
				(width 0.1)
				(type default)
			)
			(layer "F.Fab")
		)
		(pad "1" smd circle
			(at -0.40005 0 270)
			(size 0 0)
			(layers "F.Cu" "F.Mask" "F.Paste")
			(net "PVNN_TERM_CPU0")
		)
		(pad "2" smd circle
			(at 0.40005 0 270)
			(size 0 0)
			(layers "F.Cu" "F.Mask" "F.Paste")
			(net "H_CPU0_THERMTRIP_LVC1_R_N")
		)
	)
	(footprint ""
		(layer "F.Cu")
		(at 98.31705 -32.636714)
		(property "Reference" "R3520"
			(at 0 0 0)
			(layer "F.SilkS")
			(hide yes)
			(effects
				(font
					(size 1.27 1.27)
				)
			)
		)
		(property "Value" ""
			(at 0 0 0)
			(layer "F.Fab")
			(effects
				(font
					(size 1.27 1.27)
				)
			)
		)
		(duplicate_pad_numbers_are_jumpers no)
		(fp_line
			(start -0.7874 -0.4064)
			(end 0.7874 -0.4064)
			(stroke
				(width 0.1524)
				(type default)
			)
			(layer "F.SilkS")
		)
		(fp_line
			(start -0.7874 0.4064)
			(end -0.7874 -0.4064)
			(stroke
				(width 0.1524)
				(type default)
			)
			(layer "F.SilkS")
		)
		(fp_line
			(start 0.7874 -0.4064)
			(end 0.7874 0.4064)
			(stroke
				(width 0.1524)
				(type default)
			)
			(layer "F.SilkS")
		)
		(fp_line
			(start 0.7874 0.4064)
			(end -0.7874 0.4064)
			(stroke
				(width 0.1524)
				(type default)
			)
			(layer "F.SilkS")
		)
		(fp_line
			(start -0.67945 -0.305054)
			(end -0.12065 -0.305054)
			(stroke
				(width 0.1)
				(type default)
			)
			(layer "F.Fab")
		)
		(fp_line
			(start -0.67945 0.3048)
			(end -0.67945 -0.305054)
			(stroke
				(width 0.1)
				(type default)
			)
			(layer "F.Fab")
		)
		(fp_line
			(start -0.12065 -0.305054)
			(end -0.12065 -0.2794)
			(stroke
				(width 0.1)
				(type default)
			)
			(layer "F.Fab")
		)
		(fp_line
			(start -0.12065 -0.2794)
			(end 0.12065 -0.2794)
			(stroke
				(width 0.1)
				(type default)
			)
			(layer "F.Fab")
		)
		(fp_line
			(start -0.12065 0.2794)
			(end -0.12065 0.3048)
			(stroke
				(width 0.1)
				(type default)
			)
			(layer "F.Fab")
		)
		(fp_line
			(start -0.12065 0.3048)
			(end -0.67945 0.3048)
			(stroke
				(width 0.1)
				(type default)
			)
			(layer "F.Fab")
		)
		(fp_line
			(start 0.120396 0.2794)
			(end -0.12065 0.2794)
			(stroke
				(width 0.1)
				(type default)
			)
			(layer "F.Fab")
		)
		(fp_line
			(start 0.120396 0.3048)
			(end 0.120396 0.2794)
			(stroke
				(width 0.1)
				(type default)
			)
			(layer "F.Fab")
		)
		(fp_line
			(start 0.12065 -0.3048)
			(end 0.67945 -0.3048)
			(stroke
				(width 0.1)
				(type default)
			)
			(layer "F.Fab")
		)
		(fp_line
			(start 0.12065 -0.2794)
			(end 0.12065 -0.3048)
			(stroke
				(width 0.1)
				(type default)
			)
			(layer "F.Fab")
		)
		(fp_line
			(start 0.67945 -0.3048)
			(end 0.67945 0.3048)
			(stroke
				(width 0.1)
				(type default)
			)
			(layer "F.Fab")
		)
		(fp_line
			(start 0.67945 0.3048)
			(end 0.120396 0.3048)
			(stroke
				(width 0.1)
				(type default)
			)
			(layer "F.Fab")
		)
		(pad "1" smd circle
			(at -0.40005 0)
			(size 0 0)
			(layers "F.Cu" "F.Mask" "F.Paste")
			(net "P3V3_OCP_V3_2")
		)
		(pad "2" smd circle
			(at 0.40005 0)
			(size 0 0)
			(layers "F.Cu" "F.Mask" "F.Paste")
			(net "SMB_OCP_V3_2_3V3AUX_BUF_SDA")
		)
	)
	(footprint ""
		(layer "F.Cu")
		(at 421.9702 -17.612614 90)
		(property "Reference" "C861"
			(at 0 0 90)
			(layer "F.SilkS")
			(hide yes)
			(effects
				(font
					(size 1.27 1.27)
				)
			)
		)
		(property "Value" ""
			(at 0 0 90)
			(layer "F.Fab")
			(effects
				(font
					(size 1.27 1.27)
				)
			)
		)
		(duplicate_pad_numbers_are_jumpers no)
		(fp_line
			(start 0.299974 -0.150114)
			(end 0.299974 0.150114)
			(stroke
				(width 0.1)
				(type default)
			)
			(layer "F.Fab")
		)
		(fp_line
			(start -0.299974 -0.150114)
			(end 0.299974 -0.150114)
			(stroke
				(width 0.1)
				(type default)
			)
			(layer "F.Fab")
		)
		(fp_line
			(start 0.299974 0.150114)
			(end -0.299974 0.150114)
			(stroke
				(width 0.1)
				(type default)
			)
			(layer "F.Fab")
		)
		(fp_line
			(start -0.299974 0.150114)
			(end -0.299974 -0.150114)
			(stroke
				(width 0.1)
				(type default)
			)
			(layer "F.Fab")
		)
		(pad "1" smd rect
			(at -0.2667 0 90)
			(size 0.3048 0.381)
			(layers "F.Cu" "F.Mask" "F.Paste")
			(net "P5E_CPU0_PE1_TX_C_DP<4>")
		)
		(pad "2" smd rect
			(at 0.2667 0 90)
			(size 0.3048 0.381)
			(layers "F.Cu" "F.Mask" "F.Paste")
			(net "P5E_CPU0_PE1_TX_DP<4>")
		)
	)
	(footprint ""
		(layer "F.Cu")
		(at 25.9715 -396.888462 -90)
		(property "Reference" "R4663"
			(at 0 0 270)
			(layer "F.SilkS")
			(hide yes)
			(effects
				(font
					(size 1.27 1.27)
				)
			)
		)
		(property "Value" ""
			(at 0 0 270)
			(layer "F.Fab")
			(effects
				(font
					(size 1.27 1.27)
				)
			)
		)
		(duplicate_pad_numbers_are_jumpers no)
		(fp_line
			(start -0.7874 0.4064)
			(end -0.7874 -0.4064)
			(stroke
				(width 0.1524)
				(type default)
			)
			(layer "F.SilkS")
		)
		(fp_line
			(start 0.7874 0.4064)
			(end 0.003302 0.4064)
			(stroke
				(width 0.1524)
				(type default)
			)
			(layer "F.SilkS")
		)
		(fp_line
			(start -0.7874 -0.4064)
			(end 0.7874 -0.4064)
			(stroke
				(width 0.1524)
				(type default)
			)
			(layer "F.SilkS")
		)
		(fp_line
			(start -0.67945 0.3048)
			(end -0.67945 -0.305054)
			(stroke
				(width 0.1)
				(type default)
			)
			(layer "F.Fab")
		)
		(fp_line
			(start -0.12065 0.3048)
			(end -0.67945 0.3048)
			(stroke
				(width 0.1)
				(type default)
			)
			(layer "F.Fab")
		)
		(fp_line
			(start 0.120396 0.3048)
			(end 0.120396 0.2794)
			(stroke
				(width 0.1)
				(type default)
			)
			(layer "F.Fab")
		)
		(fp_line
			(start 0.67945 0.3048)
			(end 0.120396 0.3048)
			(stroke
				(width 0.1)
				(type default)
			)
			(layer "F.Fab")
		)
		(fp_line
			(start -0.12065 0.2794)
			(end -0.12065 0.3048)
			(stroke
				(width 0.1)
				(type default)
			)
			(layer "F.Fab")
		)
		(fp_line
			(start 0.120396 0.2794)
			(end -0.12065 0.2794)
			(stroke
				(width 0.1)
				(type default)
			)
			(layer "F.Fab")
		)
		(fp_line
			(start -0.12065 -0.2794)
			(end 0.12065 -0.2794)
			(stroke
				(width 0.1)
				(type default)
			)
			(layer "F.Fab")
		)
		(fp_line
			(start 0.12065 -0.2794)
			(end 0.12065 -0.3048)
			(stroke
				(width 0.1)
				(type default)
			)
			(layer "F.Fab")
		)
		(fp_line
			(start 0.12065 -0.3048)
			(end 0.67945 -0.3048)
			(stroke
				(width 0.1)
				(type default)
			)
			(layer "F.Fab")
		)
		(fp_line
			(start 0.67945 -0.3048)
			(end 0.67945 0.3048)
			(stroke
				(width 0.1)
				(type default)
			)
			(layer "F.Fab")
		)
		(fp_line
			(start -0.67945 -0.305054)
			(end -0.12065 -0.305054)
			(stroke
				(width 0.1)
				(type default)
			)
			(layer "F.Fab")
		)
		(fp_line
			(start -0.12065 -0.305054)
			(end -0.12065 -0.2794)
			(stroke
				(width 0.1)
				(type default)
			)
			(layer "F.Fab")
		)
		(pad "1" smd rect
			(at -0.40005 0 90)
			(size 0.4572 0.508)
			(layers "F.Cu" "F.Mask" "F.Paste")
			(net "P2E_MB_BMC_RX_DP<0>")
		)
		(pad "2" smd rect
			(at 0.40005 0 90)
			(size 0.4572 0.508)
			(layers "F.Cu" "F.Mask" "F.Paste")
			(net "P2E_MB_BMC_RX_R1_DP<0>")
		)
	)
	(footprint ""
		(layer "F.Cu")
		(at 248.22658 -398.78 90)
		(property "Reference" "PPQ2"
			(at -8.221472 -1.44272 0)
			(unlocked yes)
			(layer "F.SilkS")
			(effects
				(font
					(size 0.7874 0.5842)
					(thickness 0.1524)
				)
				(justify left)
			)
		)
		(property "Value" ""
			(at 0 0 90)
			(layer "F.Fab")
			(effects
				(font
					(size 1.27 1.27)
				)
			)
		)
		(duplicate_pad_numbers_are_jumpers no)
		(fp_line
			(start 2.350008 -2.649982)
			(end 2.350008 -2.4892)
			(stroke
				(width 0.1524)
				(type default)
			)
			(layer "F.SilkS")
		)
		(fp_line
			(start -2.350008 -2.649982)
			(end 2.350008 -2.649982)
			(stroke
				(width 0.1524)
				(type default)
			)
			(layer "F.SilkS")
		)
		(fp_line
			(start -2.350008 -2.4384)
			(end -2.350008 -2.649982)
			(stroke
				(width 0.1524)
				(type default)
			)
			(layer "F.SilkS")
		)
		(fp_line
			(start 2.350008 2.4892)
			(end 2.350008 2.649982)
			(stroke
				(width 0.1524)
				(type default)
			)
			(layer "F.SilkS")
		)
		(fp_line
			(start 2.350008 2.649982)
			(end -2.350008 2.649982)
			(stroke
				(width 0.1524)
				(type default)
			)
			(layer "F.SilkS")
		)
		(fp_line
			(start -2.350008 2.649982)
			(end -2.350008 2.413)
			(stroke
				(width 0.1524)
				(type default)
			)
			(layer "F.SilkS")
		)
		(fp_poly
			(pts
				(xy -3.717544 -1.905) (xy -4.758944 -2.3241) (xy -4.758944 -1.524)
			)
			(stroke
				(width 0)
				(type default)
			)
			(fill yes)
			(layer "F.SilkS")
		)
		(fp_line
			(start 2.350008 -2.649982)
			(end 2.350008 2.649982)
			(stroke
				(width 0.1)
				(type default)
			)
			(layer "F.Fab")
		)
		(fp_line
			(start -2.350008 -2.649982)
			(end 2.350008 -2.649982)
			(stroke
				(width 0.1)
				(type default)
			)
			(layer "F.Fab")
		)
		(fp_line
			(start 2.350008 2.649982)
			(end -2.350008 2.649982)
			(stroke
				(width 0.1)
				(type default)
			)
			(layer "F.Fab")
		)
		(fp_line
			(start -2.350008 2.649982)
			(end -2.350008 -2.649982)
			(stroke
				(width 0.1)
				(type default)
			)
			(layer "F.Fab")
		)
		(fp_poly
			(pts
				(xy -3.717544 -1.905) (xy -4.758944 -2.3241) (xy -4.758944 -1.524)
			)
			(stroke
				(width 0)
				(type default)
			)
			(fill yes)
			(layer "F.Fab")
		)
		(pad "1" smd rect
			(at -2.999994 -1.905)
			(size 0.7112 1.1684)
			(layers "F.Cu" "F.Mask" "F.Paste")
			(net "P12V_AUX")
		)
		(pad "2" smd rect
			(at -2.999994 -0.635)
			(size 0.7112 1.1684)
			(layers "F.Cu" "F.Mask" "F.Paste")
			(net "P12V_AUX")
		)
		(pad "3" smd rect
			(at -2.999994 0.635)
			(size 0.7112 1.1684)
			(layers "F.Cu" "F.Mask" "F.Paste")
			(net "P12V_AUX")
		)
		(pad "4" smd rect
			(at -2.999994 1.905)
			(size 0.7112 1.1684)
			(layers "F.Cu" "F.Mask" "F.Paste")
			(net "P12V_HSC_GATE_G6")
		)
		(pad "5" smd circle
			(at 0.925068 0)
			(size 0 0)
			(layers "F.Cu" "F.Mask" "F.Paste")
			(net "P12V_MAIN_R")
		)
		(zone
			(layer "F.Cu")
			(hatch none 0.5)
			(connect_pads
				(clearance 0)
			)
			(min_thickness 0.25)
			(keepout
				(tracks not_allowed)
				(vias allowed)
				(pads allowed)
				(copperpour not_allowed)
				(footprints allowed)
			)
			(placement
				(enabled no)
				(sheetname "")
			)
			(fill
				(thermal_gap 0.5)
				(thermal_bridge_width 0.5)
				(island_removal_mode 0)
			)
			(polygon
				(pts
					(xy 246.06758 -397.3322) (xy 250.38558 -397.3322) (xy 250.47702 -397.24076) (xy 250.86818 -397.24076)
					(xy 250.86818 -396.4305) (xy 245.58498 -396.4305) (xy 245.58498 -397.3322)
				)
			)
		)
	)
	(footprint ""
		(layer "F.Cu")
		(at 178.13782 -356.03053 90)
		(property "Reference" "PC1191"
			(at 0 0 90)
			(layer "F.SilkS")
			(hide yes)
			(effects
				(font
					(size 1.27 1.27)
				)
			)
		)
		(property "Value" ""
			(at 0 0 90)
			(layer "F.Fab")
			(effects
				(font
					(size 1.27 1.27)
				)
			)
		)
		(duplicate_pad_numbers_are_jumpers no)
		(fp_line
			(start 0.7874 -0.4064)
			(end 0.7874 0.4064)
			(stroke
				(width 0.1524)
				(type default)
			)
			(layer "F.SilkS")
		)
		(fp_line
			(start -0.7874 -0.4064)
			(end 0.7874 -0.4064)
			(stroke
				(width 0.1524)
				(type default)
			)
			(layer "F.SilkS")
		)
		(fp_line
			(start 0.7874 0.4064)
			(end -0.7874 0.4064)
			(stroke
				(width 0.1524)
				(type default)
			)
			(layer "F.SilkS")
		)
		(fp_line
			(start -0.7874 0.4064)
			(end -0.7874 -0.4064)
			(stroke
				(width 0.1524)
				(type default)
			)
			(layer "F.SilkS")
		)
		(fp_line
			(start -0.12065 -0.305054)
			(end -0.12065 -0.2794)
			(stroke
				(width 0.1)
				(type default)
			)
			(layer "F.Fab")
		)
		(fp_line
			(start -0.67945 -0.305054)
			(end -0.12065 -0.305054)
			(stroke
				(width 0.1)
				(type default)
			)
			(layer "F.Fab")
		)
		(fp_line
			(start 0.67945 -0.3048)
			(end 0.67945 0.3048)
			(stroke
				(width 0.1)
				(type default)
			)
			(layer "F.Fab")
		)
		(fp_line
			(start 0.12065 -0.3048)
			(end 0.67945 -0.3048)
			(stroke
				(width 0.1)
				(type default)
			)
			(layer "F.Fab")
		)
		(fp_line
			(start 0.12065 -0.2794)
			(end 0.12065 -0.3048)
			(stroke
				(width 0.1)
				(type default)
			)
			(layer "F.Fab")
		)
		(fp_line
			(start -0.12065 -0.2794)
			(end 0.12065 -0.2794)
			(stroke
				(width 0.1)
				(type default)
			)
			(layer "F.Fab")
		)
		(fp_line
			(start 0.120396 0.2794)
			(end -0.12065 0.2794)
			(stroke
				(width 0.1)
				(type default)
			)
			(layer "F.Fab")
		)
		(fp_line
			(start -0.12065 0.2794)
			(end -0.12065 0.3048)
			(stroke
				(width 0.1)
				(type default)
			)
			(layer "F.Fab")
		)
		(fp_line
			(start 0.67945 0.3048)
			(end 0.120396 0.3048)
			(stroke
				(width 0.1)
				(type default)
			)
			(layer "F.Fab")
		)
		(fp_line
			(start 0.120396 0.3048)
			(end 0.120396 0.2794)
			(stroke
				(width 0.1)
				(type default)
			)
			(layer "F.Fab")
		)
		(fp_line
			(start -0.12065 0.3048)
			(end -0.67945 0.3048)
			(stroke
				(width 0.1)
				(type default)
			)
			(layer "F.Fab")
		)
		(fp_line
			(start -0.67945 0.3048)
			(end -0.67945 -0.305054)
			(stroke
				(width 0.1)
				(type default)
			)
			(layer "F.Fab")
		)
		(pad "1" smd circle
			(at -0.40005 0 90)
			(size 0 0)
			(layers "F.Cu" "F.Mask" "F.Paste")
			(net "PVCCFA_EHV_FIVRA_CPU1_VDD3")
		)
		(pad "2" smd circle
			(at 0.40005 0 90)
			(size 0 0)
			(layers "F.Cu" "F.Mask" "F.Paste")
			(net "GND")
		)
	)
	(footprint ""
		(layer "F.Cu")
		(at 405.09317 -402.371052 -90)
		(property "Reference" "C957"
			(at 0 0 270)
			(layer "F.SilkS")
			(hide yes)
			(effects
				(font
					(size 1.27 1.27)
				)
			)
		)
		(property "Value" ""
			(at 0 0 270)
			(layer "F.Fab")
			(effects
				(font
					(size 1.27 1.27)
				)
			)
		)
		(duplicate_pad_numbers_are_jumpers no)
		(fp_line
			(start -0.299974 0.150114)
			(end -0.299974 -0.150114)
			(stroke
				(width 0.1)
				(type default)
			)
			(layer "F.Fab")
		)
		(fp_line
			(start 0.299974 0.150114)
			(end -0.299974 0.150114)
			(stroke
				(width 0.1)
				(type default)
			)
			(layer "F.Fab")
		)
		(fp_line
			(start -0.299974 -0.150114)
			(end 0.299974 -0.150114)
			(stroke
				(width 0.1)
				(type default)
			)
			(layer "F.Fab")
		)
		(fp_line
			(start 0.299974 -0.150114)
			(end 0.299974 0.150114)
			(stroke
				(width 0.1)
				(type default)
			)
			(layer "F.Fab")
		)
		(pad "1" smd rect
			(at -0.2667 0 270)
			(size 0.3048 0.381)
			(layers "F.Cu" "F.Mask" "F.Paste")
			(net "P5E_CPU0_PE2_TX_C_DP<4>")
		)
		(pad "2" smd rect
			(at 0.2667 0 270)
			(size 0.3048 0.381)
			(layers "F.Cu" "F.Mask" "F.Paste")
			(net "P5E_CPU0_PE2_TX_DP<4>")
		)
	)
)
